FILE_TYPE = MACRO_DRAWING;
SET COLOR_WIRE YELLOW;
SET COLOR_PROP ORANGE;
SET COLOR_DOT WHITE;
SET COLOR_ARC YELLOW;
SET COLOR_BODY GREEN;
SET COLOR_NOTE PURPLE;
SET PROP_DISPLAY VALUE;
SET PAGE_NUMBER P57;
SET PATH_NUMBER P51;
FORCEADD GND_POWER..1
(-2025 3300);
FORCEPROP 3 LASTPIN (-1975 3400) SIG_NAME GND\g
J 0
(-1965 3410);
DISPLAY 0.659574 (-1965 3410);
PAINT MONO (-1965 3410);
DISPLAY INVISIBLE (-1965 3410);
FORCEPROP 2 LAST CDS_LIB standard
J 0
(-2025 3300);
DISPLAY INVISIBLE (-2025 3300);
FORCEPROP 2 LAST PATH I1
J 0
(-2025 3425);
DISPLAY 1.021277 (-2025 3425);
DISPLAY INVISIBLE (-2025 3425);
FORCEPROP 1 LAST HDL_POWER GND
J 0
(-2008 3383);
DISPLAY 0.702128 (-2008 3383);
PAINT GREEN (-2008 3383);
DISPLAY INVISIBLE (-2008 3383);
FORCEPROP 1 LAST BODY_TYPE PLUMBING
J 0
(-2021 3496);
DISPLAY 0.978723 (-2021 3496);
DISPLAY INVISIBLE (-2021 3496);
FORCEPROP 0 LAST VOLTAGE 0
J 0
(-2149 3449);
DISPLAY 0.510638 (-2149 3449);
PAINT SKYBLUE (-2149 3449);
DISPLAY INVISIBLE (-2149 3449);
FORCEADD HOLE..1
(2375 3575);
FORCEPROP 2 LAST PACK_TYPE TH
J 0
(2250 3850);
DISPLAY 0.510638 (2250 3850);
PAINT SKYBLUE (2250 3850);
FORCEPROP 1 LAST MATERIAL EMPTY
J 0
(2250 3710);
DISPLAY 0.510638 (2250 3710);
PAINT RED (2250 3710);
FORCEPROP 1 LAST PART_NUMBER DUMMY50
J 0
(2250 3755);
DISPLAY 0.510638 (2250 3755);
PAINT WHITE (2250 3755);
FORCEPROP 1 LAST NEEDS_NO_SIZE TRUE
J 0
(2375 3575);
DISPLAY 0.468085 (2375 3575);
PAINT GREEN (2375 3575);
DISPLAY INVISIBLE (2375 3575);
FORCEPROP 2 LAST CDS_LIB pure_quanta
J 0
(2375 3575);
DISPLAY INVISIBLE (2375 3575);
FORCEPROP 1 LAST PATH I14
J 0
(2425 3705);
DISPLAY 0.723404 (2425 3705);
PAINT GREEN (2425 3705);
DISPLAY INVISIBLE (2425 3705);
FORCEPROP 1 LAST LOCATION H2B1
J 0
(2250 3810);
DISPLAY 0.702128 (2250 3810);
PAINT AQUA (2250 3810);
FORCEPROP 0 LASTPIN (2175 3600) $PN 1
J 2
(2165 3610);
DISPLAY 0.680851 (2165 3610);
PAINT MONO (2165 3610);
FORCEPROP 0 LAST $SEC 1
J 0
(2250 3900);
DISPLAY 0.680851 (2250 3900);
PAINT MONO (2250 3900);
DISPLAY INVISIBLE (2250 3900);
FORCEPROP 0 LAST CDS_SEC 1
J 0
(2250 3900);
DISPLAY 1.021277 (2250 3900);
DISPLAY INVISIBLE (2250 3900);
FORCEADD GND_POWER..1
(200 2700);
FORCEPROP 3 LASTPIN (250 2800) SIG_NAME GND\g
J 0
(260 2810);
DISPLAY 0.659574 (260 2810);
PAINT MONO (260 2810);
DISPLAY INVISIBLE (260 2810);
FORCEPROP 0 LAST VOLTAGE 0
J 0
(76 2849);
DISPLAY 0.510638 (76 2849);
PAINT SKYBLUE (76 2849);
DISPLAY INVISIBLE (76 2849);
FORCEPROP 2 LAST CDS_LIB standard
J 0
(200 2700);
DISPLAY INVISIBLE (200 2700);
FORCEPROP 1 LAST BODY_TYPE PLUMBING
J 0
(204 2896);
DISPLAY 0.978723 (204 2896);
DISPLAY INVISIBLE (204 2896);
FORCEPROP 1 LAST HDL_POWER GND
J 0
(217 2783);
DISPLAY 0.702128 (217 2783);
PAINT GREEN (217 2783);
DISPLAY INVISIBLE (217 2783);
FORCEPROP 2 LAST PATH I31
J 0
(150 2825);
DISPLAY 1.021277 (150 2825);
DISPLAY INVISIBLE (150 2825);
FORCEADD GND_POWER..1
(175 3275);
FORCEPROP 3 LASTPIN (225 3375) SIG_NAME GND\g
J 0
(235 3385);
DISPLAY 0.659574 (235 3385);
PAINT MONO (235 3385);
DISPLAY INVISIBLE (235 3385);
FORCEPROP 0 LAST VOLTAGE 0
J 0
(51 3424);
DISPLAY 0.510638 (51 3424);
PAINT SKYBLUE (51 3424);
DISPLAY INVISIBLE (51 3424);
FORCEPROP 2 LAST CDS_LIB standard
J 0
(175 3275);
DISPLAY INVISIBLE (175 3275);
FORCEPROP 1 LAST BODY_TYPE PLUMBING
J 0
(179 3471);
DISPLAY 0.978723 (179 3471);
DISPLAY INVISIBLE (179 3471);
FORCEPROP 1 LAST HDL_POWER GND
J 0
(192 3358);
DISPLAY 0.702128 (192 3358);
PAINT GREEN (192 3358);
DISPLAY INVISIBLE (192 3358);
FORCEPROP 2 LAST PATH I33
J 0
(125 3400);
DISPLAY 1.021277 (125 3400);
DISPLAY INVISIBLE (125 3400);
FORCEADD HOLE..1
(2375 3050);
FORCEPROP 1 LAST PART_NUMBER DUMMY50
J 0
(2250 3230);
DISPLAY 0.510638 (2250 3230);
PAINT WHITE (2250 3230);
FORCEPROP 2 LAST PACK_TYPE TH
J 0
(2250 3325);
DISPLAY 0.510638 (2250 3325);
PAINT SKYBLUE (2250 3325);
FORCEPROP 1 LAST MATERIAL EMPTY
J 0
(2250 3185);
DISPLAY 0.510638 (2250 3185);
PAINT RED (2250 3185);
FORCEPROP 2 LAST CDS_LIB pure_quanta
J 0
(2375 3050);
DISPLAY INVISIBLE (2375 3050);
FORCEPROP 1 LAST NEEDS_NO_SIZE TRUE
J 0
(2375 3050);
DISPLAY 0.468085 (2375 3050);
PAINT GREEN (2375 3050);
DISPLAY INVISIBLE (2375 3050);
FORCEPROP 1 LAST PATH I34
J 0
(2425 3180);
DISPLAY 0.723404 (2425 3180);
PAINT GREEN (2425 3180);
DISPLAY INVISIBLE (2425 3180);
FORCEPROP 1 LAST LOCATION H2B2
J 0
(2250 3285);
DISPLAY 0.702128 (2250 3285);
PAINT AQUA (2250 3285);
FORCEPROP 0 LASTPIN (2175 3075) $PN 1
J 2
(2165 3085);
DISPLAY 0.680851 (2165 3085);
PAINT MONO (2165 3085);
FORCEPROP 0 LAST $SEC 1
J 0
(2250 3350);
DISPLAY 0.680851 (2250 3350);
PAINT MONO (2250 3350);
DISPLAY INVISIBLE (2250 3350);
FORCEPROP 0 LAST CDS_SEC 1
J 0
(2250 3350);
DISPLAY 1.021277 (2250 3350);
DISPLAY INVISIBLE (2250 3350);
FORCEADD HOLE..1
(-1675 3600);
FORCEPROP 2 LAST PACK_TYPE TH
J 0
(-1800 3875);
DISPLAY 0.510638 (-1800 3875);
PAINT SKYBLUE (-1800 3875);
FORCEPROP 1 LAST MATERIAL EMPTY
J 0
(-1800 3735);
DISPLAY 0.510638 (-1800 3735);
PAINT RED (-1800 3735);
FORCEPROP 1 LAST PART_NUMBER HOLE1211
J 0
(-1800 3780);
DISPLAY 0.510638 (-1800 3780);
PAINT WHITE (-1800 3780);
FORCEPROP 1 LAST PATH I35
J 0
(-1625 3730);
DISPLAY 0.723404 (-1625 3730);
PAINT GREEN (-1625 3730);
DISPLAY INVISIBLE (-1625 3730);
FORCEPROP 1 LAST NEEDS_NO_SIZE TRUE
J 0
(-1675 3600);
DISPLAY 0.468085 (-1675 3600);
PAINT GREEN (-1675 3600);
DISPLAY INVISIBLE (-1675 3600);
FORCEPROP 2 LAST CDS_LIB pure_quanta
J 0
(-1675 3600);
DISPLAY INVISIBLE (-1675 3600);
FORCEPROP 1 LAST LOCATION H5
J 0
(-1800 3835);
DISPLAY 0.702128 (-1800 3835);
PAINT AQUA (-1800 3835);
FORCEPROP 0 LASTPIN (-1875 3625) $PN 1
J 2
(-1885 3635);
DISPLAY 0.680851 (-1885 3635);
PAINT MONO (-1885 3635);
FORCEPROP 0 LAST $SEC 1
J 0
(-1800 3900);
DISPLAY 0.680851 (-1800 3900);
PAINT MONO (-1800 3900);
DISPLAY INVISIBLE (-1800 3900);
FORCEPROP 0 LAST CDS_SEC 1
J 0
(-1800 3900);
DISPLAY 1.021277 (-1800 3900);
DISPLAY INVISIBLE (-1800 3900);
FORCEADD HOLE..1
(-1650 2975);
FORCEPROP 1 LAST MATERIAL EMPTY
J 0
(-1775 3110);
DISPLAY 0.510638 (-1775 3110);
PAINT RED (-1775 3110);
FORCEPROP 1 LAST PART_NUMBER HOLE1211
J 0
(-1775 3155);
DISPLAY 0.510638 (-1775 3155);
PAINT WHITE (-1775 3155);
FORCEPROP 2 LAST PACK_TYPE TH
J 0
(-1775 3250);
DISPLAY 0.510638 (-1775 3250);
PAINT SKYBLUE (-1775 3250);
FORCEPROP 1 LAST NEEDS_NO_SIZE TRUE
J 0
(-1650 2975);
DISPLAY 0.468085 (-1650 2975);
PAINT GREEN (-1650 2975);
DISPLAY INVISIBLE (-1650 2975);
FORCEPROP 2 LAST CDS_LIB pure_quanta
J 0
(-1650 2975);
DISPLAY INVISIBLE (-1650 2975);
FORCEPROP 1 LAST PATH I36
J 0
(-1600 3105);
DISPLAY 0.723404 (-1600 3105);
PAINT GREEN (-1600 3105);
DISPLAY INVISIBLE (-1600 3105);
FORCEPROP 1 LAST LOCATION H9
J 0
(-1775 3210);
DISPLAY 0.702128 (-1775 3210);
PAINT YELLOW (-1775 3210);
FORCEPROP 0 LASTPIN (-1850 3000) $PN 1
J 2
(-1860 3010);
DISPLAY 0.680851 (-1860 3010);
PAINT MONO (-1860 3010);
FORCEPROP 0 LAST $SEC 1
J 0
(-1775 3275);
DISPLAY 0.680851 (-1775 3275);
PAINT MONO (-1775 3275);
DISPLAY INVISIBLE (-1775 3275);
FORCEPROP 0 LAST CDS_SEC 1
J 0
(-1775 3275);
DISPLAY 1.021277 (-1775 3275);
DISPLAY INVISIBLE (-1775 3275);
FORCEADD GND_POWER..1
(-2000 2675);
FORCEPROP 3 LASTPIN (-1950 2775) SIG_NAME GND\g
J 0
(-1940 2785);
DISPLAY 0.659574 (-1940 2785);
PAINT MONO (-1940 2785);
DISPLAY INVISIBLE (-1940 2785);
FORCEPROP 0 LAST VOLTAGE 0
J 0
(-2124 2824);
DISPLAY 0.510638 (-2124 2824);
PAINT SKYBLUE (-2124 2824);
DISPLAY INVISIBLE (-2124 2824);
FORCEPROP 2 LAST CDS_LIB standard
J 0
(-2000 2675);
DISPLAY INVISIBLE (-2000 2675);
FORCEPROP 1 LAST BODY_TYPE PLUMBING
J 0
(-1996 2871);
DISPLAY 0.978723 (-1996 2871);
DISPLAY INVISIBLE (-1996 2871);
FORCEPROP 1 LAST HDL_POWER GND
J 0
(-1983 2758);
DISPLAY 0.702128 (-1983 2758);
PAINT GREEN (-1983 2758);
DISPLAY INVISIBLE (-1983 2758);
FORCEPROP 0 LAST PATH I37
J 0
(-2050 2800);
DISPLAY 1.021277 (-2050 2800);
DISPLAY INVISIBLE (-2050 2800);
FORCEADD HOLE..1
(-1625 1425);
FORCEPROP 2 LAST PACK_TYPE TH
J 0
(-1750 1700);
DISPLAY 0.680851 (-1750 1700);
FORCEPROP 1 LAST MATERIAL EMPTY
J 0
(-1750 1560);
DISPLAY 0.723404 (-1750 1560);
PAINT GREEN (-1750 1560);
FORCEPROP 1 LAST PART_NUMBER HOLE620
J 0
(-1750 1605);
DISPLAY 0.723404 (-1750 1605);
PAINT GREEN (-1750 1605);
FORCEPROP 2 LAST CDS_LIB pure_quanta
J 0
(-1625 1425);
DISPLAY INVISIBLE (-1625 1425);
FORCEPROP 1 LAST PATH I38
J 0
(-1575 1555);
DISPLAY 0.723404 (-1575 1555);
PAINT GREEN (-1575 1555);
DISPLAY INVISIBLE (-1575 1555);
FORCEPROP 1 LAST NEEDS_NO_SIZE TRUE
J 0
(-1625 1425);
DISPLAY 0.468085 (-1625 1425);
PAINT GREEN (-1625 1425);
DISPLAY INVISIBLE (-1625 1425);
FORCEPROP 1 LAST $LOCATION H3
J 0
(-1750 1660);
DISPLAY 0.723404 (-1750 1660);
PAINT GREEN (-1750 1660);
FORCEPROP 0 LASTPIN (-1825 1450) $PN 1
J 2
(-1835 1460);
DISPLAY 0.680851 (-1835 1460);
PAINT MONO (-1835 1460);
FORCEPROP 0 LAST CDS_LOCATION H3
J 0
(-1750 1750);
DISPLAY 0.680851 (-1750 1750);
DISPLAY INVISIBLE (-1750 1750);
FORCEPROP 0 LAST $SEC 1
J 0
(-1750 1750);
DISPLAY 0.680851 (-1750 1750);
PAINT MONO (-1750 1750);
DISPLAY INVISIBLE (-1750 1750);
FORCEPROP 0 LAST CDS_SEC 1
J 0
(-1750 1750);
DISPLAY 0.680851 (-1750 1750);
DISPLAY INVISIBLE (-1750 1750);
FORCEADD GND_POWER..1
(-1975 1125);
FORCEPROP 3 LASTPIN (-1925 1225) SIG_NAME GND\g
J 0
(-1915 1235);
DISPLAY 0.659574 (-1915 1235);
PAINT MONO (-1915 1235);
DISPLAY INVISIBLE (-1915 1235);
FORCEPROP 2 LAST PATH I39
J 0
(-1975 1250);
DISPLAY 0.680851 (-1975 1250);
FORCEPROP 2 LAST CDS_LIB standard
J 0
(-1975 1125);
DISPLAY INVISIBLE (-1975 1125);
FORCEPROP 1 LAST HDL_POWER GND
J 0
(-1958 1208);
DISPLAY 0.702128 (-1958 1208);
PAINT GREEN (-1958 1208);
DISPLAY INVISIBLE (-1958 1208);
FORCEPROP 1 LAST BODY_TYPE PLUMBING
J 0
(-1971 1321);
DISPLAY 0.978723 (-1971 1321);
DISPLAY INVISIBLE (-1971 1321);
FORCEPROP 0 LAST VOLTAGE 0
J 0
(-2099 1274);
DISPLAY 0.510638 (-2099 1274);
PAINT SKYBLUE (-2099 1274);
DISPLAY INVISIBLE (-2099 1274);
FORCEADD HOLE..1
(-1625 550);
FORCEPROP 1 LAST PART_NUMBER HOLE620
J 0
(-1750 730);
DISPLAY 0.723404 (-1750 730);
PAINT GREEN (-1750 730);
FORCEPROP 1 LAST MATERIAL EMPTY
J 0
(-1750 685);
DISPLAY 0.723404 (-1750 685);
PAINT GREEN (-1750 685);
FORCEPROP 2 LAST PACK_TYPE TH
J 0
(-1750 825);
DISPLAY 0.680851 (-1750 825);
FORCEPROP 1 LAST NEEDS_NO_SIZE TRUE
J 0
(-1625 550);
DISPLAY 0.468085 (-1625 550);
PAINT GREEN (-1625 550);
DISPLAY INVISIBLE (-1625 550);
FORCEPROP 1 LAST PATH I40
J 0
(-1575 680);
DISPLAY 0.723404 (-1575 680);
PAINT GREEN (-1575 680);
DISPLAY INVISIBLE (-1575 680);
FORCEPROP 2 LAST CDS_LIB pure_quanta
J 0
(-1625 550);
DISPLAY INVISIBLE (-1625 550);
FORCEPROP 1 LAST $LOCATION H4
J 0
(-1750 785);
DISPLAY 0.723404 (-1750 785);
PAINT GREEN (-1750 785);
FORCEPROP 0 LASTPIN (-1825 575) $PN 1
J 2
(-1835 585);
DISPLAY 0.680851 (-1835 585);
PAINT MONO (-1835 585);
FORCEPROP 0 LAST CDS_LOCATION H4
J 0
(-1750 875);
DISPLAY 0.680851 (-1750 875);
DISPLAY INVISIBLE (-1750 875);
FORCEPROP 0 LAST $SEC 1
J 0
(-1750 875);
DISPLAY 0.680851 (-1750 875);
PAINT MONO (-1750 875);
DISPLAY INVISIBLE (-1750 875);
FORCEPROP 0 LAST CDS_SEC 1
J 0
(-1750 875);
DISPLAY 0.680851 (-1750 875);
DISPLAY INVISIBLE (-1750 875);
FORCEADD GND_POWER..1
(-1975 250);
FORCEPROP 3 LASTPIN (-1925 350) SIG_NAME GND\g
J 0
(-1915 360);
DISPLAY 0.659574 (-1915 360);
PAINT MONO (-1915 360);
DISPLAY INVISIBLE (-1915 360);
FORCEPROP 2 LAST PATH I41
J 0
(-1975 375);
DISPLAY 0.680851 (-1975 375);
FORCEPROP 0 LAST VOLTAGE 0
J 0
(-2099 399);
DISPLAY 0.510638 (-2099 399);
PAINT SKYBLUE (-2099 399);
DISPLAY INVISIBLE (-2099 399);
FORCEPROP 1 LAST BODY_TYPE PLUMBING
J 0
(-1971 446);
DISPLAY 0.978723 (-1971 446);
DISPLAY INVISIBLE (-1971 446);
FORCEPROP 1 LAST HDL_POWER GND
J 0
(-1958 333);
DISPLAY 0.702128 (-1958 333);
PAINT GREEN (-1958 333);
DISPLAY INVISIBLE (-1958 333);
FORCEPROP 2 LAST CDS_LIB standard
J 0
(-1975 250);
DISPLAY INVISIBLE (-1975 250);
FORCEADD GND_POWER..1
(150 1175);
FORCEPROP 3 LASTPIN (200 1275) SIG_NAME GND\g
J 0
(210 1285);
DISPLAY 0.659574 (210 1285);
PAINT MONO (210 1285);
DISPLAY INVISIBLE (210 1285);
FORCEPROP 2 LAST PATH I43
J 0
(150 1300);
DISPLAY 0.680851 (150 1300);
FORCEPROP 1 LAST HDL_POWER GND
J 0
(167 1258);
DISPLAY 0.702128 (167 1258);
PAINT GREEN (167 1258);
DISPLAY INVISIBLE (167 1258);
FORCEPROP 1 LAST BODY_TYPE PLUMBING
J 0
(154 1371);
DISPLAY 0.978723 (154 1371);
DISPLAY INVISIBLE (154 1371);
FORCEPROP 0 LAST VOLTAGE 0
J 0
(26 1324);
DISPLAY 0.510638 (26 1324);
PAINT SKYBLUE (26 1324);
DISPLAY INVISIBLE (26 1324);
FORCEPROP 2 LAST CDS_LIB standard
J 0
(150 1175);
DISPLAY INVISIBLE (150 1175);
FORCEADD HOLE..1
(525 650);
FORCEPROP 1 LAST PART_NUMBER HOLE1247
J 0
(400 830);
DISPLAY 0.723404 (400 830);
PAINT GREEN (400 830);
FORCEPROP 1 LAST MATERIAL EMPTY
J 0
(400 785);
DISPLAY 0.723404 (400 785);
PAINT GREEN (400 785);
FORCEPROP 2 LAST PACK_TYPE TH
J 0
(400 925);
DISPLAY 0.680851 (400 925);
FORCEPROP 2 LAST CDS_LIB pure_quanta
J 0
(525 650);
DISPLAY INVISIBLE (525 650);
FORCEPROP 1 LAST PATH I45
J 0
(575 780);
DISPLAY 0.723404 (575 780);
PAINT GREEN (575 780);
DISPLAY INVISIBLE (575 780);
FORCEPROP 1 LAST NEEDS_NO_SIZE TRUE
J 0
(525 650);
DISPLAY 0.468085 (525 650);
PAINT GREEN (525 650);
DISPLAY INVISIBLE (525 650);
FORCEPROP 1 LAST $LOCATION H2
J 0
(400 885);
DISPLAY 0.723404 (400 885);
PAINT GREEN (400 885);
FORCEPROP 0 LASTPIN (325 675) $PN 1
J 2
(315 685);
DISPLAY 0.680851 (315 685);
PAINT MONO (315 685);
FORCEPROP 0 LAST CDS_LOCATION H2
J 0
(400 975);
DISPLAY 0.680851 (400 975);
DISPLAY INVISIBLE (400 975);
FORCEPROP 0 LAST $SEC 1
J 0
(400 975);
DISPLAY 0.680851 (400 975);
PAINT MONO (400 975);
DISPLAY INVISIBLE (400 975);
FORCEPROP 0 LAST CDS_SEC 1
J 0
(400 975);
DISPLAY 0.680851 (400 975);
DISPLAY INVISIBLE (400 975);
FORCEADD HOLE..1
(500 1475);
FORCEPROP 2 LAST PACK_TYPE TH
J 0
(375 1750);
DISPLAY 0.680851 (375 1750);
FORCEPROP 1 LAST PART_NUMBER HOLE1248
J 0
(375 1655);
DISPLAY 0.723404 (375 1655);
PAINT GREEN (375 1655);
FORCEPROP 1 LAST MATERIAL EMPTY
J 0
(375 1610);
DISPLAY 0.723404 (375 1610);
PAINT GREEN (375 1610);
FORCEPROP 1 LAST NEEDS_NO_SIZE TRUE
J 0
(500 1475);
DISPLAY 0.468085 (500 1475);
PAINT GREEN (500 1475);
DISPLAY INVISIBLE (500 1475);
FORCEPROP 1 LAST PATH I49
J 0
(550 1605);
DISPLAY 0.723404 (550 1605);
PAINT GREEN (550 1605);
DISPLAY INVISIBLE (550 1605);
FORCEPROP 2 LAST CDS_LIB pure_quanta
J 0
(500 1475);
DISPLAY INVISIBLE (500 1475);
FORCEPROP 1 LAST LOCATION H1
J 0
(375 1710);
DISPLAY 0.723404 (375 1710);
PAINT GREEN (375 1710);
FORCEPROP 0 LASTPIN (300 1500) $PN 1
J 2
(290 1510);
DISPLAY 0.680851 (290 1510);
PAINT MONO (290 1510);
FORCEPROP 0 LAST $SEC 1
J 0
(375 1800);
DISPLAY 0.680851 (375 1800);
PAINT MONO (375 1800);
DISPLAY INVISIBLE (375 1800);
FORCEPROP 0 LAST CDS_SEC 1
J 0
(375 1800);
DISPLAY 0.680851 (375 1800);
DISPLAY INVISIBLE (375 1800);
FORCEADD HOLE..1
(525 3575);
FORCEPROP 1 LAST MATERIAL EMPTY
J 0
(400 3710);
DISPLAY 0.723404 (400 3710);
PAINT GREEN (400 3710);
FORCEPROP 1 LAST PART_NUMBER TMP-C_HOLE8
J 0
(400 3755);
DISPLAY 0.723404 (400 3755);
PAINT GREEN (400 3755);
FORCEPROP 2 LAST PACK_TYPE TH
J 0
(400 3850);
DISPLAY 0.680851 (400 3850);
FORCEPROP 1 LAST NEEDS_NO_SIZE TRUE
J 0
(525 3575);
DISPLAY 0.468085 (525 3575);
PAINT GREEN (525 3575);
DISPLAY INVISIBLE (525 3575);
FORCEPROP 1 LAST PATH I50
J 0
(575 3705);
DISPLAY 0.723404 (575 3705);
PAINT GREEN (575 3705);
DISPLAY INVISIBLE (575 3705);
FORCEPROP 2 LAST CDS_LIB pure_quanta
J 0
(525 3575);
DISPLAY INVISIBLE (525 3575);
FORCEPROP 1 LAST LOCATION H6
J 0
(400 3810);
DISPLAY 0.723404 (400 3810);
PAINT GREEN (400 3810);
FORCEPROP 0 LASTPIN (325 3600) $PN 1
J 2
(315 3610);
DISPLAY 0.680851 (315 3610);
PAINT MONO (315 3610);
FORCEPROP 0 LAST $SEC 1
J 0
(400 3900);
DISPLAY 0.680851 (400 3900);
PAINT MONO (400 3900);
DISPLAY INVISIBLE (400 3900);
FORCEPROP 0 LAST CDS_SEC 1
J 0
(400 3900);
DISPLAY 0.680851 (400 3900);
DISPLAY INVISIBLE (400 3900);
FORCEADD HOLE..1
(550 3000);
FORCEPROP 1 LAST MATERIAL EMPTY
J 0
(425 3135);
DISPLAY 0.723404 (425 3135);
PAINT GREEN (425 3135);
FORCEPROP 1 LAST PART_NUMBER TMP-C_HOLE8
J 0
(425 3180);
DISPLAY 0.723404 (425 3180);
PAINT GREEN (425 3180);
FORCEPROP 2 LAST PACK_TYPE TH
J 0
(425 3275);
DISPLAY 0.680851 (425 3275);
FORCEPROP 2 LAST CDS_LIB pure_quanta
J 0
(550 3000);
DISPLAY INVISIBLE (550 3000);
FORCEPROP 1 LAST PATH I51
J 0
(600 3130);
DISPLAY 0.723404 (600 3130);
PAINT GREEN (600 3130);
DISPLAY INVISIBLE (600 3130);
FORCEPROP 1 LAST NEEDS_NO_SIZE TRUE
J 0
(550 3000);
DISPLAY 0.468085 (550 3000);
PAINT GREEN (550 3000);
DISPLAY INVISIBLE (550 3000);
FORCEPROP 1 LAST LOCATION H7
J 0
(425 3235);
DISPLAY 0.723404 (425 3235);
PAINT GREEN (425 3235);
FORCEPROP 0 LASTPIN (350 3025) $PN 1
J 2
(340 3035);
DISPLAY 0.680851 (340 3035);
PAINT MONO (340 3035);
FORCEPROP 0 LAST $SEC 1
J 0
(425 3325);
DISPLAY 0.680851 (425 3325);
PAINT MONO (425 3325);
DISPLAY INVISIBLE (425 3325);
FORCEPROP 0 LAST CDS_SEC 1
J 0
(425 3325);
DISPLAY 0.680851 (425 3325);
DISPLAY INVISIBLE (425 3325);
FORCEADD QUANTA_TITLE_BLOCK_C..1
(5700 -1250);
FORCEPROP 0 LAST CDS_CON_LAST_MODIFIED Fri Aug 25 17:25:50 2023
J 0
(3815 -1235);
DISPLAY INVISIBLE (3815 -1235);
FORCEPROP 2 LAST Q_DEPT 
J 1
(1937 -1201);
DISPLAY 1.957447 (1937 -1201);
PAINT GREEN (1937 -1201);
FORCEPROP 1 LAST CUSTOM_TXT_CDS <CON_LAST_MODIFIED>
J 0
(3815 -1235);
DISPLAY 0.978723 (3815 -1235);
FORCEPROP 2 LAST CUSTOM_TXT_CDS <XR_PAGE_TITLE>
J 0
(-2190 4000);
DISPLAY 0.638298 (-2190 4000);
PAINT PINK (-2190 4000);
DISPLAY INVISIBLE (-2190 4000);
FORCEPROP 1 LAST CUSTOM_TXT_CDS <NAME_2>
J 0
(2525 -1200);
FORCEPROP 1 LAST CUSTOM_TXT_CDS <NAME_1>
J 0
(2525 -1075);
FORCEPROP 1 LAST CUSTOM_TXT_CDS <Q_NUMBER>
J 0
(4297 -1147);
DISPLAY 1.212766 (4297 -1147);
FORCEPROP 1 LAST CUSTOM_TXT_CDS <Q_PROJ>
J 0
(3318 -1148);
DISPLAY 1.212766 (3318 -1148);
FORCEPROP 1 LAST CUSTOM_TXT_CDS <Q_REV>
J 0
(5516 -1147);
DISPLAY 1.212766 (5516 -1147);
FORCEPROP 1 LAST CUSTOM_TXT_CDS <CON_PAGE_NUM> OF <CON_TOTAL_PAGES>
J 0
(5254 -1232);
DISPLAY 0.978723 (5254 -1232);
FORCEPROP 1 LAST Q_TITLE HOLES
J 0
(-3666 -1224);
DISPLAY 2.446809 (-3666 -1224);
PAINT GREEN (-3666 -1224);
FORCEPROP 1 LAST COMMENT_BODY TRUE
J 0
(5712 -1263);
DISPLAY 0.978723 (5712 -1263);
PAINT PEACH (5712 -1263);
DISPLAY INVISIBLE (5712 -1263);
FORCEPROP 2 LAST PAGE_BORDER TRUE
J 0
(-2190 4000);
DISPLAY 0.638298 (-2190 4000);
PAINT PINK (-2190 4000);
DISPLAY INVISIBLE (-2190 4000);
FORCEPROP 1 LAST CDS_LMAN_SYM_OUTLINE -9475,6775,100,-125
J 0
(5700 -1250);
DISPLAY 0.468085 (5700 -1250);
PAINT GREEN (5700 -1250);
DISPLAY INVISIBLE (5700 -1250);
FORCEPROP 2 LAST CDS_LIB pure_quanta
J 0
(5700 -1250);
DISPLAY INVISIBLE (5700 -1250);
FORCEPROP 2 LAST CDS_XR_PAGE_TITLE CR-57 : @SCM_LIB.SCM(SCH_1):PAGE57
J 0
(-2190 4000);
DISPLAY 0.638298 (-2190 4000);
PAINT PINK (-2190 4000);
DISPLAY INVISIBLE (-2190 4000);
FORCEADD DNS..3
(525 675);
PAINT RED (525 675);
FORCEPROP 2 LAST CDS_LIB mstr_misc
J 0
(525 675);
DISPLAY INVISIBLE (525 675);
FORCEPROP 1 LAST COMMENT_BODY TRUE
R 1
J 0
(600 450);
DISPLAY 0.872340 (600 450);
PAINT PEACH (600 450);
DISPLAY INVISIBLE (600 450);
FORCEADD BOM_NOTE..1
(150 4150);
FORCEPROP 0 LAST L BOT NUT
J 0
(105 3995);
DISPLAY 1.021277 (105 3995);
PAINT WHITE (105 3995);
FORCEPROP 2 LAST CDS_LIB logical_power
J 0
(150 4150);
DISPLAY INVISIBLE (150 4150);
FORCEPROP 1 LAST COMMENT_BODY TRUE
J 0
(175 4250);
DISPLAY 0.978723 (175 4250);
PAINT PEACH (175 4250);
DISPLAY INVISIBLE (175 4250);
FORCEADD DNS..3
(2370 3080);
PAINT RED (2370 3080);
FORCEPROP 2 LAST CDS_LIB mstr_misc
J 0
(2370 3080);
DISPLAY INVISIBLE (2370 3080);
FORCEPROP 1 LAST COMMENT_BODY TRUE
R 1
J 0
(2445 2855);
DISPLAY 0.872340 (2445 2855);
PAINT PEACH (2445 2855);
DISPLAY INVISIBLE (2445 2855);
FORCEADD BOM_NOTE..1
(2295 4150);
FORCEPROP 0 LAST L TOOLING HOLE
J 0
(2250 3995);
DISPLAY 1.021277 (2250 3995);
PAINT WHITE (2250 3995);
FORCEPROP 2 LAST CDS_LIB logical_power
J 0
(2295 4150);
DISPLAY INVISIBLE (2295 4150);
FORCEPROP 1 LAST COMMENT_BODY TRUE
J 0
(2320 4250);
DISPLAY 0.978723 (2320 4250);
PAINT PEACH (2320 4250);
DISPLAY INVISIBLE (2320 4250);
FORCEADD DNS..3
(2370 3605);
PAINT RED (2370 3605);
FORCEPROP 2 LAST CDS_LIB mstr_misc
J 0
(2370 3605);
DISPLAY INVISIBLE (2370 3605);
FORCEPROP 1 LAST COMMENT_BODY TRUE
R 1
J 0
(2445 3380);
DISPLAY 0.872340 (2445 3380);
PAINT PEACH (2445 3380);
DISPLAY INVISIBLE (2445 3380);
FORCEADD DNS..3
(-1650 3000);
PAINT RED (-1650 3000);
FORCEPROP 2 LAST CDS_LIB mstr_misc
J 0
(-1650 3000);
DISPLAY INVISIBLE (-1650 3000);
FORCEPROP 1 LAST COMMENT_BODY TRUE
R 1
J 0
(-1575 2775);
DISPLAY 0.872340 (-1575 2775);
PAINT PEACH (-1575 2775);
DISPLAY INVISIBLE (-1575 2775);
FORCEADD BOM_NOTE..1
(-1950 4150);
FORCEPROP 0 LAST L TOP NUT
J 0
(-1995 3995);
DISPLAY 1.021277 (-1995 3995);
PAINT WHITE (-1995 3995);
FORCEPROP 1 LAST COMMENT_BODY TRUE
J 0
(-1925 4250);
DISPLAY 0.978723 (-1925 4250);
PAINT PEACH (-1925 4250);
DISPLAY INVISIBLE (-1925 4250);
FORCEPROP 2 LAST CDS_LIB logical_power
J 0
(-1950 4150);
DISPLAY INVISIBLE (-1950 4150);
FORCEADD BOM_NOTE..1
(-1950 2025);
FORCEPROP 0 LAST L TPM NUT
J 0
(-1995 1870);
DISPLAY 1.021277 (-1995 1870);
PAINT WHITE (-1995 1870);
FORCEPROP 1 LAST COMMENT_BODY TRUE
J 0
(-1925 2125);
DISPLAY 0.978723 (-1925 2125);
PAINT PEACH (-1925 2125);
DISPLAY INVISIBLE (-1925 2125);
FORCEPROP 2 LAST CDS_LIB logical_power
J 0
(-1950 2025);
DISPLAY INVISIBLE (-1950 2025);
FORCEADD BOM_NOTE..1
(150 2025);
FORCEPROP 0 LAST L BSM NUT
J 0
(105 1870);
DISPLAY 1.021277 (105 1870);
PAINT WHITE (105 1870);
FORCEPROP 1 LAST COMMENT_BODY TRUE
J 0
(175 2125);
DISPLAY 0.978723 (175 2125);
PAINT PEACH (175 2125);
DISPLAY INVISIBLE (175 2125);
FORCEPROP 2 LAST CDS_LIB logical_power
J 0
(150 2025);
DISPLAY INVISIBLE (150 2025);
WIRE 16 -1 (225 3375)(225 3600);
WIRE 16 -1 (250 2800)(250 3025);
WIRE 16 -1 (-1975 3400)(-1975 3625);
WIRE 16 -1 (-1950 2775)(-1950 3000);
WIRE 16 -1 (-1925 1225)(-1925 1450);
WIRE 16 -1 (-1925 350)(-1925 575);
WIRE 16 -1 (200 1275)(200 1500);
WIRE 16 -1 (-1875 3625)(-1975 3625);
WIRE 16 -1 (350 3025)(250 3025);
WIRE 16 -1 (325 3600)(225 3600);
WIRE 16 -1 (-1850 3000)(-1950 3000);
WIRE 16 -1 (-1825 1450)(-1925 1450);
WIRE 16 -1 (-1825 575)(-1925 575);
WIRE 16 -1 (300 1500)(200 1500);
QUIT
